(kicad_pcb
	(version 20260206)
	(generator "pcbnew")
	(generator_version "10.0")
	(general
		(thickness 1.6)
		(legacy_teardrops no)
	)
	(paper "A4")
	(title_block
		(title "12092022_DA0F0TFB6D0_F0T_FAN_BOARD_MP5048_D_brd_v02_OCP.brd")
		(comment 1 "Grand Teton / footprints 904-910 of 924")
	)
	(layers
		(0 "F.Cu" signal "TOP")
		(4 "In1.Cu" signal "GND")
		(6 "In2.Cu" signal "IN1")
		(8 "In3.Cu" signal "IN2")
		(10 "In4.Cu" signal "GND1")
		(2 "B.Cu" signal "BOTTOM")
		(9 "F.Adhes" user "F.Adhesive")
		(11 "B.Adhes" user "B.Adhesive")
		(13 "F.Paste" user "Package Geometry/Pastemask Top")
		(15 "B.Paste" user "Package Geometry/Pastemask Bottom")
		(5 "F.SilkS" user "Ref Des/Silkscreen Top")
		(7 "B.SilkS" user "Ref Des/Silkscreen Bottom")
		(1 "F.Mask" user "Board Geometry/Soldermask Top")
		(3 "B.Mask" user "Board Geometry/Soldermask Bottom")
		(17 "Dwgs.User" user "User.Drawings")
		(19 "Cmts.User" user "User.Comments")
		(21 "Eco1.User" user "User.Eco1")
		(23 "Eco2.User" user "User.Eco2")
		(25 "Edge.Cuts" user "Board Geometry/Outline")
		(27 "Margin" user)
		(31 "F.CrtYd" user "Package Geometry/Place Bound Top")
		(29 "B.CrtYd" user "Package Geometry/Place Bound Bottom")
		(35 "F.Fab" user "Ref Des/Assembly Top")
		(33 "B.Fab" user "Ref Des/Assembly Bottom")
	)
	(footprint ""
		(layer "B.Cu")
		(at 40.894 -133.477 180)
		(property "Reference" "R5428"
			(at 0 0 0)
			(layer "B.SilkS")
			(hide yes)
			(effects
				(font
					(size 1.27 1.27)
				)
				(justify mirror)
			)
		)
		(property "Value" ""
			(at 0 0 0)
			(layer "B.Fab")
			(effects
				(font
					(size 1.27 1.27)
				)
				(justify mirror)
			)
		)
		(duplicate_pad_numbers_are_jumpers no)
		(fp_line
			(start 0.7874 0.4064)
			(end 0.7874 -0.4064)
			(stroke
				(width 0.1524)
				(type default)
			)
			(layer "B.SilkS")
		)
		(fp_line
			(start 0.7874 -0.4064)
			(end -0.7874 -0.4064)
			(stroke
				(width 0.1524)
				(type default)
			)
			(layer "B.SilkS")
		)
		(fp_line
			(start -0.7874 0.4064)
			(end 0.7874 0.4064)
			(stroke
				(width 0.1524)
				(type default)
			)
			(layer "B.SilkS")
		)
		(fp_line
			(start -0.7874 -0.4064)
			(end -0.7874 0.4064)
			(stroke
				(width 0.1524)
				(type default)
			)
			(layer "B.SilkS")
		)
		(fp_line
			(start 0.67945 0.3048)
			(end 0.67945 -0.305054)
			(stroke
				(width 0.1)
				(type default)
			)
			(layer "B.Fab")
		)
		(fp_line
			(start 0.67945 -0.305054)
			(end 0.12065 -0.305054)
			(stroke
				(width 0.1)
				(type default)
			)
			(layer "B.Fab")
		)
		(fp_line
			(start 0.12065 0.3048)
			(end 0.67945 0.3048)
			(stroke
				(width 0.1)
				(type default)
			)
			(layer "B.Fab")
		)
		(fp_line
			(start 0.12065 0.2794)
			(end 0.12065 0.3048)
			(stroke
				(width 0.1)
				(type default)
			)
			(layer "B.Fab")
		)
		(fp_line
			(start 0.12065 -0.2794)
			(end -0.12065 -0.2794)
			(stroke
				(width 0.1)
				(type default)
			)
			(layer "B.Fab")
		)
		(fp_line
			(start 0.12065 -0.305054)
			(end 0.12065 -0.2794)
			(stroke
				(width 0.1)
				(type default)
			)
			(layer "B.Fab")
		)
		(fp_line
			(start -0.120396 0.3048)
			(end -0.120396 0.2794)
			(stroke
				(width 0.1)
				(type default)
			)
			(layer "B.Fab")
		)
		(fp_line
			(start -0.120396 0.2794)
			(end 0.12065 0.2794)
			(stroke
				(width 0.1)
				(type default)
			)
			(layer "B.Fab")
		)
		(fp_line
			(start -0.12065 -0.2794)
			(end -0.12065 -0.3048)
			(stroke
				(width 0.1)
				(type default)
			)
			(layer "B.Fab")
		)
		(fp_line
			(start -0.12065 -0.3048)
			(end -0.67945 -0.3048)
			(stroke
				(width 0.1)
				(type default)
			)
			(layer "B.Fab")
		)
		(fp_line
			(start -0.67945 0.3048)
			(end -0.120396 0.3048)
			(stroke
				(width 0.1)
				(type default)
			)
			(layer "B.Fab")
		)
		(fp_line
			(start -0.67945 -0.3048)
			(end -0.67945 0.3048)
			(stroke
				(width 0.1)
				(type default)
			)
			(layer "B.Fab")
		)
		(pad "1" smd rect
			(at 0.40005 0 180)
			(size 0.4572 0.508)
			(layers "B.Cu" "B.Mask" "B.Paste")
			(net "FAN_1_TACH_IL")
		)
		(pad "2" smd rect
			(at -0.40005 0 180)
			(size 0.4572 0.508)
			(layers "B.Cu" "B.Mask" "B.Paste")
			(net "GND")
		)
	)
	(footprint ""
		(layer "B.Cu")
		(at 44.704 -50.165 180)
		(property "Reference" "C2105"
			(at 0 0 0)
			(layer "B.SilkS")
			(hide yes)
			(effects
				(font
					(size 1.27 1.27)
				)
				(justify mirror)
			)
		)
		(property "Value" ""
			(at 0 0 0)
			(layer "B.Fab")
			(effects
				(font
					(size 1.27 1.27)
				)
				(justify mirror)
			)
		)
		(duplicate_pad_numbers_are_jumpers no)
		(fp_line
			(start 2.2098 0.9398)
			(end 2.2098 -0.9398)
			(stroke
				(width 0.1524)
				(type default)
			)
			(layer "B.SilkS")
		)
		(fp_line
			(start 2.2098 -0.9398)
			(end -2.2098 -0.9398)
			(stroke
				(width 0.1524)
				(type default)
			)
			(layer "B.SilkS")
		)
		(fp_line
			(start -2.2098 0.9398)
			(end 2.2098 0.9398)
			(stroke
				(width 0.1524)
				(type default)
			)
			(layer "B.SilkS")
		)
		(fp_line
			(start -2.2098 -0.9398)
			(end -2.2098 0.9398)
			(stroke
				(width 0.1524)
				(type default)
			)
			(layer "B.SilkS")
		)
		(fp_line
			(start 1.700022 0.899922)
			(end 1.700022 -0.899922)
			(stroke
				(width 0.1)
				(type default)
			)
			(layer "B.Fab")
		)
		(fp_line
			(start 1.700022 -0.899922)
			(end -1.700022 -0.899922)
			(stroke
				(width 0.1)
				(type default)
			)
			(layer "B.Fab")
		)
		(fp_line
			(start -1.700022 0.899922)
			(end 1.700022 0.899922)
			(stroke
				(width 0.1)
				(type default)
			)
			(layer "B.Fab")
		)
		(fp_line
			(start -1.700022 -0.899922)
			(end -1.700022 0.899922)
			(stroke
				(width 0.1)
				(type default)
			)
			(layer "B.Fab")
		)
		(pad "1" smd rect
			(at 1.4732 0 180)
			(size 1.1684 1.5748)
			(layers "B.Cu" "B.Mask" "B.Paste")
			(net "P52V_FAN_3")
		)
		(pad "2" smd rect
			(at -1.4732 0 180)
			(size 1.1684 1.5748)
			(layers "B.Cu" "B.Mask" "B.Paste")
			(net "GND")
		)
	)
	(footprint ""
		(layer "B.Cu")
		(at 17.653 -131.953 180)
		(property "Reference" "R5440"
			(at 0 0 0)
			(layer "B.SilkS")
			(hide yes)
			(effects
				(font
					(size 1.27 1.27)
				)
				(justify mirror)
			)
		)
		(property "Value" ""
			(at 0 0 0)
			(layer "B.Fab")
			(effects
				(font
					(size 1.27 1.27)
				)
				(justify mirror)
			)
		)
		(duplicate_pad_numbers_are_jumpers no)
		(fp_line
			(start 0.7874 0.4064)
			(end 0.7874 -0.4064)
			(stroke
				(width 0.1524)
				(type default)
			)
			(layer "B.SilkS")
		)
		(fp_line
			(start 0.7874 -0.4064)
			(end -0.7874 -0.4064)
			(stroke
				(width 0.1524)
				(type default)
			)
			(layer "B.SilkS")
		)
		(fp_line
			(start -0.7874 0.4064)
			(end 0.7874 0.4064)
			(stroke
				(width 0.1524)
				(type default)
			)
			(layer "B.SilkS")
		)
		(fp_line
			(start -0.7874 -0.4064)
			(end -0.7874 0.4064)
			(stroke
				(width 0.1524)
				(type default)
			)
			(layer "B.SilkS")
		)
		(fp_line
			(start 0.67945 0.3048)
			(end 0.67945 -0.305054)
			(stroke
				(width 0.1)
				(type default)
			)
			(layer "B.Fab")
		)
		(fp_line
			(start 0.67945 -0.305054)
			(end 0.12065 -0.305054)
			(stroke
				(width 0.1)
				(type default)
			)
			(layer "B.Fab")
		)
		(fp_line
			(start 0.12065 0.3048)
			(end 0.67945 0.3048)
			(stroke
				(width 0.1)
				(type default)
			)
			(layer "B.Fab")
		)
		(fp_line
			(start 0.12065 0.2794)
			(end 0.12065 0.3048)
			(stroke
				(width 0.1)
				(type default)
			)
			(layer "B.Fab")
		)
		(fp_line
			(start 0.12065 -0.2794)
			(end -0.12065 -0.2794)
			(stroke
				(width 0.1)
				(type default)
			)
			(layer "B.Fab")
		)
		(fp_line
			(start 0.12065 -0.305054)
			(end 0.12065 -0.2794)
			(stroke
				(width 0.1)
				(type default)
			)
			(layer "B.Fab")
		)
		(fp_line
			(start -0.120396 0.3048)
			(end -0.120396 0.2794)
			(stroke
				(width 0.1)
				(type default)
			)
			(layer "B.Fab")
		)
		(fp_line
			(start -0.120396 0.2794)
			(end 0.12065 0.2794)
			(stroke
				(width 0.1)
				(type default)
			)
			(layer "B.Fab")
		)
		(fp_line
			(start -0.12065 -0.2794)
			(end -0.12065 -0.3048)
			(stroke
				(width 0.1)
				(type default)
			)
			(layer "B.Fab")
		)
		(fp_line
			(start -0.12065 -0.3048)
			(end -0.67945 -0.3048)
			(stroke
				(width 0.1)
				(type default)
			)
			(layer "B.Fab")
		)
		(fp_line
			(start -0.67945 0.3048)
			(end -0.120396 0.3048)
			(stroke
				(width 0.1)
				(type default)
			)
			(layer "B.Fab")
		)
		(fp_line
			(start -0.67945 -0.3048)
			(end -0.67945 0.3048)
			(stroke
				(width 0.1)
				(type default)
			)
			(layer "B.Fab")
		)
		(pad "1" smd rect
			(at 0.40005 0 180)
			(size 0.4572 0.508)
			(layers "B.Cu" "B.Mask" "B.Paste")
			(net "FAN_7_TACH_IL")
		)
		(pad "2" smd rect
			(at -0.40005 0 180)
			(size 0.4572 0.508)
			(layers "B.Cu" "B.Mask" "B.Paste")
			(net "GND")
		)
	)
	(footprint ""
		(layer "B.Cu")
		(at 5.596128 -232.755948)
		(property "Reference" "C2116"
			(at 0 0 0)
			(layer "B.SilkS")
			(hide yes)
			(effects
				(font
					(size 1.27 1.27)
				)
				(justify mirror)
			)
		)
		(property "Value" ""
			(at 0 0 0)
			(layer "B.Fab")
			(effects
				(font
					(size 1.27 1.27)
				)
				(justify mirror)
			)
		)
		(duplicate_pad_numbers_are_jumpers no)
		(fp_line
			(start -2.2098 -0.9398)
			(end -2.2098 0.9398)
			(stroke
				(width 0.1524)
				(type default)
			)
			(layer "B.SilkS")
		)
		(fp_line
			(start -2.2098 0.9398)
			(end 2.2098 0.9398)
			(stroke
				(width 0.1524)
				(type default)
			)
			(layer "B.SilkS")
		)
		(fp_line
			(start 2.2098 -0.9398)
			(end -2.2098 -0.9398)
			(stroke
				(width 0.1524)
				(type default)
			)
			(layer "B.SilkS")
		)
		(fp_line
			(start 2.2098 0.9398)
			(end 2.2098 -0.9398)
			(stroke
				(width 0.1524)
				(type default)
			)
			(layer "B.SilkS")
		)
		(fp_line
			(start -1.700022 -0.899922)
			(end -1.700022 0.899922)
			(stroke
				(width 0.1)
				(type default)
			)
			(layer "B.Fab")
		)
		(fp_line
			(start -1.700022 0.899922)
			(end 1.700022 0.899922)
			(stroke
				(width 0.1)
				(type default)
			)
			(layer "B.Fab")
		)
		(fp_line
			(start 1.700022 -0.899922)
			(end -1.700022 -0.899922)
			(stroke
				(width 0.1)
				(type default)
			)
			(layer "B.Fab")
		)
		(fp_line
			(start 1.700022 0.899922)
			(end 1.700022 -0.899922)
			(stroke
				(width 0.1)
				(type default)
			)
			(layer "B.Fab")
		)
		(pad "1" smd rect
			(at 1.4732 0)
			(size 1.1684 1.5748)
			(layers "B.Cu" "B.Mask" "B.Paste")
			(net "P52V_FAN_6")
		)
		(pad "2" smd rect
			(at -1.4732 0)
			(size 1.1684 1.5748)
			(layers "B.Cu" "B.Mask" "B.Paste")
			(net "GND")
		)
	)
	(footprint ""
		(layer "B.Cu")
		(at 9.906 -170.815 180)
		(property "Reference" "C1941"
			(at 0 0 0)
			(layer "B.SilkS")
			(hide yes)
			(effects
				(font
					(size 1.27 1.27)
				)
				(justify mirror)
			)
		)
		(property "Value" ""
			(at 0 0 0)
			(layer "B.Fab")
			(effects
				(font
					(size 1.27 1.27)
				)
				(justify mirror)
			)
		)
		(duplicate_pad_numbers_are_jumpers no)
		(fp_line
			(start 0.7874 0.4064)
			(end 0.7874 -0.4064)
			(stroke
				(width 0.1524)
				(type default)
			)
			(layer "B.SilkS")
		)
		(fp_line
			(start 0.7874 -0.4064)
			(end -0.7874 -0.4064)
			(stroke
				(width 0.1524)
				(type default)
			)
			(layer "B.SilkS")
		)
		(fp_line
			(start -0.7874 0.4064)
			(end 0.7874 0.4064)
			(stroke
				(width 0.1524)
				(type default)
			)
			(layer "B.SilkS")
		)
		(fp_line
			(start -0.7874 -0.4064)
			(end -0.7874 0.4064)
			(stroke
				(width 0.1524)
				(type default)
			)
			(layer "B.SilkS")
		)
		(fp_line
			(start 0.67945 0.3048)
			(end 0.67945 -0.305054)
			(stroke
				(width 0.1)
				(type default)
			)
			(layer "B.Fab")
		)
		(fp_line
			(start 0.67945 -0.305054)
			(end 0.12065 -0.305054)
			(stroke
				(width 0.1)
				(type default)
			)
			(layer "B.Fab")
		)
		(fp_line
			(start 0.12065 0.3048)
			(end 0.67945 0.3048)
			(stroke
				(width 0.1)
				(type default)
			)
			(layer "B.Fab")
		)
		(fp_line
			(start 0.12065 0.2794)
			(end 0.12065 0.3048)
			(stroke
				(width 0.1)
				(type default)
			)
			(layer "B.Fab")
		)
		(fp_line
			(start 0.12065 -0.2794)
			(end -0.12065 -0.2794)
			(stroke
				(width 0.1)
				(type default)
			)
			(layer "B.Fab")
		)
		(fp_line
			(start 0.12065 -0.305054)
			(end 0.12065 -0.2794)
			(stroke
				(width 0.1)
				(type default)
			)
			(layer "B.Fab")
		)
		(fp_line
			(start -0.120396 0.3048)
			(end -0.120396 0.2794)
			(stroke
				(width 0.1)
				(type default)
			)
			(layer "B.Fab")
		)
		(fp_line
			(start -0.120396 0.2794)
			(end 0.12065 0.2794)
			(stroke
				(width 0.1)
				(type default)
			)
			(layer "B.Fab")
		)
		(fp_line
			(start -0.12065 -0.2794)
			(end -0.12065 -0.3048)
			(stroke
				(width 0.1)
				(type default)
			)
			(layer "B.Fab")
		)
		(fp_line
			(start -0.12065 -0.3048)
			(end -0.67945 -0.3048)
			(stroke
				(width 0.1)
				(type default)
			)
			(layer "B.Fab")
		)
		(fp_line
			(start -0.67945 0.3048)
			(end -0.120396 0.3048)
			(stroke
				(width 0.1)
				(type default)
			)
			(layer "B.Fab")
		)
		(fp_line
			(start -0.67945 -0.3048)
			(end -0.67945 0.3048)
			(stroke
				(width 0.1)
				(type default)
			)
			(layer "B.Fab")
		)
		(pad "1" smd circle
			(at 0.40005 0)
			(size 0 0)
			(layers "B.Cu" "B.Mask" "B.Paste")
			(net "P3V3_AUX")
		)
		(pad "2" smd circle
			(at -0.40005 0)
			(size 0 0)
			(layers "B.Cu" "B.Mask" "B.Paste")
			(net "GND")
		)
	)
	(footprint ""
		(layer "B.Cu")
		(at 39.116 -64.837056 -90)
		(property "Reference" "PC18"
			(at 0 0 90)
			(layer "B.SilkS")
			(hide yes)
			(effects
				(font
					(size 1.27 1.27)
				)
				(justify mirror)
			)
		)
		(property "Value" ""
			(at 0 0 90)
			(layer "B.Fab")
			(effects
				(font
					(size 1.27 1.27)
				)
				(justify mirror)
			)
		)
		(duplicate_pad_numbers_are_jumpers no)
		(fp_line
			(start -0.7874 0.4064)
			(end 0.7874 0.4064)
			(stroke
				(width 0.1524)
				(type default)
			)
			(layer "B.SilkS")
		)
		(fp_line
			(start 0.7874 0.4064)
			(end 0.7874 -0.4064)
			(stroke
				(width 0.1524)
				(type default)
			)
			(layer "B.SilkS")
		)
		(fp_line
			(start -0.7874 -0.4064)
			(end -0.7874 0.4064)
			(stroke
				(width 0.1524)
				(type default)
			)
			(layer "B.SilkS")
		)
		(fp_line
			(start 0.7874 -0.4064)
			(end -0.7874 -0.4064)
			(stroke
				(width 0.1524)
				(type default)
			)
			(layer "B.SilkS")
		)
		(fp_line
			(start -0.67945 0.3048)
			(end -0.120396 0.3048)
			(stroke
				(width 0.1)
				(type default)
			)
			(layer "B.Fab")
		)
		(fp_line
			(start -0.120396 0.3048)
			(end -0.120396 0.2794)
			(stroke
				(width 0.1)
				(type default)
			)
			(layer "B.Fab")
		)
		(fp_line
			(start 0.12065 0.3048)
			(end 0.67945 0.3048)
			(stroke
				(width 0.1)
				(type default)
			)
			(layer "B.Fab")
		)
		(fp_line
			(start 0.67945 0.3048)
			(end 0.67945 -0.305054)
			(stroke
				(width 0.1)
				(type default)
			)
			(layer "B.Fab")
		)
		(fp_line
			(start -0.120396 0.2794)
			(end 0.12065 0.2794)
			(stroke
				(width 0.1)
				(type default)
			)
			(layer "B.Fab")
		)
		(fp_line
			(start 0.12065 0.2794)
			(end 0.12065 0.3048)
			(stroke
				(width 0.1)
				(type default)
			)
			(layer "B.Fab")
		)
		(fp_line
			(start -0.12065 -0.2794)
			(end -0.12065 -0.3048)
			(stroke
				(width 0.1)
				(type default)
			)
			(layer "B.Fab")
		)
		(fp_line
			(start 0.12065 -0.2794)
			(end -0.12065 -0.2794)
			(stroke
				(width 0.1)
				(type default)
			)
			(layer "B.Fab")
		)
		(fp_line
			(start -0.67945 -0.3048)
			(end -0.67945 0.3048)
			(stroke
				(width 0.1)
				(type default)
			)
			(layer "B.Fab")
		)
		(fp_line
			(start -0.12065 -0.3048)
			(end -0.67945 -0.3048)
			(stroke
				(width 0.1)
				(type default)
			)
			(layer "B.Fab")
		)
		(fp_line
			(start 0.12065 -0.305054)
			(end 0.12065 -0.2794)
			(stroke
				(width 0.1)
				(type default)
			)
			(layer "B.Fab")
		)
		(fp_line
			(start 0.67945 -0.305054)
			(end 0.12065 -0.305054)
			(stroke
				(width 0.1)
				(type default)
			)
			(layer "B.Fab")
		)
		(pad "1" smd circle
			(at 0.40005 0 90)
			(size 0 0)
			(layers "B.Cu" "B.Mask" "B.Paste")
			(net "FAN_3_P3V_R")
		)
		(pad "2" smd circle
			(at -0.40005 0 90)
			(size 0 0)
			(layers "B.Cu" "B.Mask" "B.Paste")
			(net "GND")
		)
	)
	(footprint ""
		(layer "B.Cu")
		(at 12.207494 -71.304912)
		(property "Reference" "U361"
			(at -0.142494 1.862582 0)
			(unlocked yes)
			(layer "B.SilkS")
			(effects
				(font
					(size 0.7874 0.5842)
					(thickness 0.1524)
				)
				(justify mirror)
			)
		)
		(property "Value" ""
			(at 0 0 0)
			(layer "B.Fab")
			(effects
				(font
					(size 1.27 1.27)
				)
				(justify mirror)
			)
		)
		(duplicate_pad_numbers_are_jumpers no)
		(fp_line
			(start -1.7018 -1.1176)
			(end -1.7018 1.1176)
			(stroke
				(width 0.1524)
				(type default)
			)
			(layer "B.SilkS")
		)
		(fp_line
			(start -1.7018 -1.1176)
			(end -0.254 -1.1176)
			(stroke
				(width 0.1524)
				(type default)
			)
			(layer "B.SilkS")
		)
		(fp_line
			(start -1.7018 1.1176)
			(end 1.7018 1.1176)
			(stroke
				(width 0.1524)
				(type default)
			)
			(layer "B.SilkS")
		)
		(fp_line
			(start -0.254 -1.1176)
			(end 0 -0.7112)
			(stroke
				(width 0.1524)
				(type default)
			)
			(layer "B.SilkS")
		)
		(fp_line
			(start 0 -0.7112)
			(end 0.254 -1.1176)
			(stroke
				(width 0.1524)
				(type default)
			)
			(layer "B.SilkS")
		)
		(fp_line
			(start 0.254 -1.1176)
			(end 1.7018 -1.1176)
			(stroke
				(width 0.1524)
				(type default)
			)
			(layer "B.SilkS")
		)
		(fp_line
			(start 1.7018 1.1176)
			(end 1.7018 -1.1176)
			(stroke
				(width 0.1524)
				(type default)
			)
			(layer "B.SilkS")
		)
		(fp_poly
			(pts
				(xy 1.8161 -0.675386) (xy 2.4003 -0.446786) (xy 2.4003 -0.878586)
			)
			(stroke
				(width 0)
				(type default)
			)
			(fill yes)
			(layer "B.SilkS")
		)
		(fp_line
			(start -1.5494 -1.1176)
			(end -1.5494 1.1176)
			(stroke
				(width 0.1)
				(type default)
			)
			(layer "B.Fab")
		)
		(fp_line
			(start -1.5494 -1.1176)
			(end -0.254 -1.1176)
			(stroke
				(width 0.1)
				(type default)
			)
			(layer "B.Fab")
		)
		(fp_line
			(start -1.5494 1.1176)
			(end 1.5494 1.1176)
			(stroke
				(width 0.1)
				(type default)
			)
			(layer "B.Fab")
		)
		(fp_line
			(start -0.254 -1.1176)
			(end 0.254 -1.1176)
			(stroke
				(width 0.1)
				(type default)
			)
			(layer "B.Fab")
		)
		(fp_line
			(start 0.254 -1.1176)
			(end 1.5494 -1.1176)
			(stroke
				(width 0.1)
				(type default)
			)
			(layer "B.Fab")
		)
		(fp_line
			(start 1.5494 1.1176)
			(end 1.5494 -1.1176)
			(stroke
				(width 0.1)
				(type default)
			)
			(layer "B.Fab")
		)
		(fp_poly
			(pts
				(xy 1.8161 -0.675386) (xy 2.4003 -0.446786) (xy 2.4003 -0.878586)
			)
			(stroke
				(width 0)
				(type default)
			)
			(fill yes)
			(layer "B.Fab")
		)
		(pad "1" smd rect
			(at 0.962406 -0.649986 270)
			(size 0.3302 1.1684)
			(layers "B.Cu" "B.Mask" "B.Paste")
			(net "FAN_5_PRESENT_R")
		)
		(pad "2" smd rect
			(at 0.962406 0 270)
			(size 0.3302 1.1684)
			(layers "B.Cu" "B.Mask" "B.Paste")
			(net "P52V_FAN_5_BUFF_EN_R")
		)
		(pad "3" smd rect
			(at 0.962406 0.649986 270)
			(size 0.3302 1.1684)
			(layers "B.Cu" "B.Mask" "B.Paste")
			(net "GND")
		)
		(pad "4" smd rect
			(at -0.962406 0.649986 270)
			(size 0.3302 1.1684)
			(layers "B.Cu" "B.Mask" "B.Paste")
			(net "P52V_FAN_5_EN")
		)
		(pad "5" smd rect
			(at -0.962406 -0.649986 270)
			(size 0.3302 1.1684)
			(layers "B.Cu" "B.Mask" "B.Paste")
			(net "P3V3_AUX")
		)
	)
)
